(kicad_pcb
	(version 20260206)
	(generator "pcbnew")
	(generator_version "10.0")
	(general
		(thickness 1.6)
		(legacy_teardrops no)
	)
	(paper "A4")
	(title_block
		(title "fcb — 12433-1M.1206WZS1330.brd")
		(comment 1 "Open Vault / Knox (Wiwynn) / footprints 85-92 of 495")
	)
	(layers
		(0 "F.Cu" signal "TOP")
		(4 "In1.Cu" signal "L2GND")
		(6 "In2.Cu" signal "L3VCC")
		(2 "B.Cu" signal "BOTTOM")
		(9 "F.Adhes" user "F.Adhesive")
		(11 "B.Adhes" user "B.Adhesive")
		(13 "F.Paste" user "Package Geometry/Pastemask Top")
		(15 "B.Paste" user "Package Geometry/Pastemask Bottom")
		(5 "F.SilkS" user "Ref Des/Silkscreen Top")
		(7 "B.SilkS" user "Ref Des/Silkscreen Bottom")
		(1 "F.Mask" user "Board Geometry/Soldermask Top")
		(3 "B.Mask" user "Board Geometry/Soldermask Bottom")
		(17 "Dwgs.User" user "User.Drawings")
		(19 "Cmts.User" user "User.Comments")
		(21 "Eco1.User" user "User.Eco1")
		(23 "Eco2.User" user "User.Eco2")
		(25 "Edge.Cuts" user "Board Geometry/Outline")
		(27 "Margin" user)
		(31 "F.CrtYd" user "Package Geometry/Place Bound Top")
		(29 "B.CrtYd" user "Package Geometry/Place Bound Bottom")
		(35 "F.Fab" user "Ref Des/Assembly Top")
		(33 "B.Fab" user "Ref Des/Assembly Bottom")
	)
	(footprint ""
		(layer "F.Cu")
		(at 29.1084 -170.3324 90)
		(property "Reference" "R176"
			(at 0 0 90)
			(layer "F.SilkS")
			(hide yes)
			(effects
				(font
					(size 1.27 1.27)
				)
			)
		)
		(property "Value" "0R2J-2-GP"
			(at 0.064008 -3.993896 90)
			(unlocked yes)
			(layer "F.Fab")
			(hide yes)
			(effects
				(font
					(size 1.016 1.016)
					(thickness 0.1524)
				)
			)
		)
		(property "Device Type" "R402H16"
			(at 0.064008 -5.517896 90)
			(unlocked yes)
			(layer "F.Fab")
			(hide yes)
			(effects
				(font
					(size 1.016 1.016)
					(thickness 0.1524)
				)
			)
		)
		(duplicate_pad_numbers_are_jumpers no)
		(fp_line
			(start 0.508 -0.9398)
			(end -0.508 -0.9398)
			(stroke
				(width 0.1524)
				(type default)
			)
			(layer "F.SilkS")
		)
		(fp_line
			(start -0.508 -0.9398)
			(end -0.508 0.9398)
			(stroke
				(width 0.1524)
				(type default)
			)
			(layer "F.SilkS")
		)
		(fp_rect
			(start -0.508 0.9398)
			(end 0.508 -0.9398)
			(stroke
				(width 0)
				(type default)
			)
			(fill no)
			(layer "F.CrtYd")
		)
		(fp_rect
			(start -0.508 0.9398)
			(end 0.508 -0.9398)
			(stroke
				(width 0)
				(type default)
			)
			(fill no)
			(layer "F.Fab")
		)
		(pad "1" smd custom
			(at 0 -0.4445 90)
			(size 0.1397 0.1397)
			(layers "F.Cu" "F.Mask" "F.Paste")
			(net "PWM_OUT")
			(options
				(clearance outline)
				(anchor circle)
			)
			(primitives
				(gr_poly
					(pts
						(arc
							(start -0.1778 -0.2794)
							(mid -0.249642 -0.249642)
							(end -0.2794 -0.1778)
						)
						(arc
							(start -0.2794 0.1778)
							(mid -0.249642 0.249642)
							(end -0.1778 0.2794)
						)
						(arc
							(start 0.1778 0.2794)
							(mid 0.249642 0.249642)
							(end 0.2794 0.1778)
						)
						(arc
							(start 0.2794 -0.1778)
							(mid 0.249642 -0.249642)
							(end 0.1778 -0.2794)
						)
					)
					(width 0)
					(fill yes)
				)
			)
		)
		(pad "2" smd custom
			(at 0 0.4445 90)
			(size 0.1397 0.1397)
			(layers "F.Cu" "F.Mask" "F.Paste")
			(net "PWM_BUFFER_IN_FAN1_FAN2")
			(options
				(clearance outline)
				(anchor circle)
			)
			(primitives
				(gr_poly
					(pts
						(arc
							(start -0.1778 -0.2794)
							(mid -0.249642 -0.249642)
							(end -0.2794 -0.1778)
						)
						(arc
							(start -0.2794 0.1778)
							(mid -0.249642 0.249642)
							(end -0.1778 0.2794)
						)
						(arc
							(start 0.1778 0.2794)
							(mid 0.249642 0.249642)
							(end 0.2794 0.1778)
						)
						(arc
							(start 0.2794 -0.1778)
							(mid 0.249642 -0.249642)
							(end 0.1778 -0.2794)
						)
					)
					(width 0)
					(fill yes)
				)
			)
		)
	)
	(footprint ""
		(layer "F.Cu")
		(at 14.8844 -45.5422 90)
		(property "Reference" "R114"
			(at 0 0 90)
			(layer "F.SilkS")
			(hide yes)
			(effects
				(font
					(size 1.27 1.27)
				)
			)
		)
		(property "Value" "470R2F-GP"
			(at 0.064008 -3.993896 90)
			(unlocked yes)
			(layer "F.Fab")
			(hide yes)
			(effects
				(font
					(size 1.016 1.016)
					(thickness 0.1524)
				)
			)
		)
		(property "Device Type" "R402H16"
			(at 0.064008 -5.517896 90)
			(unlocked yes)
			(layer "F.Fab")
			(hide yes)
			(effects
				(font
					(size 1.016 1.016)
					(thickness 0.1524)
				)
			)
		)
		(duplicate_pad_numbers_are_jumpers no)
		(fp_line
			(start 0.508 -0.9398)
			(end -0.508 -0.9398)
			(stroke
				(width 0.1524)
				(type default)
			)
			(layer "F.SilkS")
		)
		(fp_line
			(start -0.508 -0.9398)
			(end -0.508 0.9398)
			(stroke
				(width 0.1524)
				(type default)
			)
			(layer "F.SilkS")
		)
		(fp_rect
			(start -0.508 0.9398)
			(end 0.508 -0.9398)
			(stroke
				(width 0)
				(type default)
			)
			(fill no)
			(layer "F.CrtYd")
		)
		(fp_rect
			(start -0.508 0.9398)
			(end 0.508 -0.9398)
			(stroke
				(width 0)
				(type default)
			)
			(fill no)
			(layer "F.Fab")
		)
		(pad "1" smd custom
			(at 0 -0.4445 90)
			(size 0.1397 0.1397)
			(layers "F.Cu" "F.Mask" "F.Paste")
			(net "SEB_PEER_1A_HB")
			(options
				(clearance outline)
				(anchor circle)
			)
			(primitives
				(gr_poly
					(pts
						(arc
							(start -0.1778 -0.2794)
							(mid -0.249642 -0.249642)
							(end -0.2794 -0.1778)
						)
						(arc
							(start -0.2794 0.1778)
							(mid -0.249642 0.249642)
							(end -0.1778 0.2794)
						)
						(arc
							(start 0.1778 0.2794)
							(mid 0.249642 0.249642)
							(end 0.2794 0.1778)
						)
						(arc
							(start 0.2794 -0.1778)
							(mid 0.249642 -0.249642)
							(end 0.1778 -0.2794)
						)
					)
					(width 0)
					(fill yes)
				)
			)
		)
		(pad "2" smd custom
			(at 0 0.4445 90)
			(size 0.1397 0.1397)
			(layers "F.Cu" "F.Mask" "F.Paste")
			(net "GND")
			(options
				(clearance outline)
				(anchor circle)
			)
			(primitives
				(gr_poly
					(pts
						(arc
							(start -0.1778 -0.2794)
							(mid -0.249642 -0.249642)
							(end -0.2794 -0.1778)
						)
						(arc
							(start -0.2794 0.1778)
							(mid -0.249642 0.249642)
							(end -0.1778 0.2794)
						)
						(arc
							(start 0.1778 0.2794)
							(mid 0.249642 0.249642)
							(end 0.2794 0.1778)
						)
						(arc
							(start 0.2794 -0.1778)
							(mid 0.249642 -0.249642)
							(end 0.1778 -0.2794)
						)
					)
					(width 0)
					(fill yes)
				)
			)
		)
	)
	(footprint ""
		(layer "F.Cu")
		(at 36.659566 -152.08631 90)
		(property "Reference" "TP14"
			(at 0 0 90)
			(layer "F.SilkS")
			(hide yes)
			(effects
				(font
					(size 1.27 1.27)
				)
			)
		)
		(property "Value" "TPAD32-GP"
			(at 0 -3.166364 90)
			(unlocked yes)
			(layer "F.Fab")
			(hide yes)
			(effects
				(font
					(size 1.016 1.016)
					(thickness 0.1524)
				)
			)
		)
		(property "Device Type" "TPAD32"
			(at 0 -4.690618 90)
			(unlocked yes)
			(layer "F.Fab")
			(hide yes)
			(effects
				(font
					(size 1.016 1.016)
					(thickness 0.1524)
				)
			)
		)
		(duplicate_pad_numbers_are_jumpers no)
		(fp_poly
			(pts
				(arc
					(start 0.7112 0)
					(mid -0.7112 0)
					(end 0.7112 0)
				)
			)
			(stroke
				(width 0)
				(type default)
			)
			(fill no)
			(layer "F.CrtYd")
		)
		(fp_poly
			(pts
				(arc
					(start 0.7112 0)
					(mid -0.7112 0)
					(end 0.7112 0)
				)
			)
			(stroke
				(width 0)
				(type default)
			)
			(fill no)
			(layer "F.Fab")
		)
		(pad "1" smd circle
			(at 0 0 90)
			(size 0.8128 0.8128)
			(layers "F.Cu" "F.Mask" "F.Paste")
			(net "NCT7904_VSEN14")
		)
	)
	(footprint ""
		(layer "F.Cu")
		(at 14.224 -157.353 180)
		(property "Reference" "R181"
			(at 0 0 180)
			(layer "F.SilkS")
			(hide yes)
			(effects
				(font
					(size 1.27 1.27)
				)
			)
		)
		(property "Value" "0R1206-PAD-1-GP"
			(at 0 -5.0292 180)
			(unlocked yes)
			(layer "F.Fab")
			(hide yes)
			(effects
				(font
					(size 1.016 1.016)
					(thickness 0.1524)
				)
			)
		)
		(property "Device Type" "0R1206-PAD-1"
			(at 0 -6.5532 180)
			(unlocked yes)
			(layer "F.Fab")
			(hide yes)
			(effects
				(font
					(size 1.016 1.016)
					(thickness 0.1524)
				)
			)
		)
		(duplicate_pad_numbers_are_jumpers no)
		(fp_line
			(start 1.016 2.2352)
			(end 1.016 -2.2352)
			(stroke
				(width 0.1524)
				(type default)
			)
			(layer "F.SilkS")
		)
		(fp_line
			(start 1.016 -2.2352)
			(end -1.016 -2.2352)
			(stroke
				(width 0.1524)
				(type default)
			)
			(layer "F.SilkS")
		)
		(fp_line
			(start -1.016 2.2352)
			(end 1.016 2.2352)
			(stroke
				(width 0.1524)
				(type default)
			)
			(layer "F.SilkS")
		)
		(fp_line
			(start -1.016 -2.2352)
			(end -1.016 2.2352)
			(stroke
				(width 0.1524)
				(type default)
			)
			(layer "F.SilkS")
		)
		(fp_rect
			(start -1.0922 2.3114)
			(end 1.0922 -2.3114)
			(stroke
				(width 0)
				(type default)
			)
			(fill no)
			(layer "F.CrtYd")
		)
		(fp_poly
			(pts
				(xy -1.0922 -2.3114) (xy 1.0922 -2.3114) (xy 1.0922 2.3114) (xy -1.0922 2.3114)
			)
			(stroke
				(width 0)
				(type default)
			)
			(fill no)
			(layer "F.Fab")
		)
		(pad "1" smd rect
			(at 0 -1.397 180)
			(size 1.651 2.0574)
			(drill
				(offset 0 0.3937)
			)
			(layers "F.Cu" "F.Mask" "F.Paste")
			(net "P12V_FAN5")
		)
		(pad "2" smd rect
			(at 0 1.397 180)
			(size 1.651 2.0574)
			(drill
				(offset 0 -0.3937)
			)
			(layers "F.Cu" "F.Mask" "F.Paste")
			(net "P12V")
		)
	)
	(footprint ""
		(layer "F.Cu")
		(at 30.3784 -210.8454 180)
		(property "Reference" "R139"
			(at 0 0 180)
			(layer "F.SilkS")
			(hide yes)
			(effects
				(font
					(size 1.27 1.27)
				)
			)
		)
		(property "Value" "0R2J-2-GP"
			(at 0.064008 -3.993896 180)
			(unlocked yes)
			(layer "F.Fab")
			(hide yes)
			(effects
				(font
					(size 1.016 1.016)
					(thickness 0.1524)
				)
			)
		)
		(property "Device Type" "R402H16"
			(at 0.064008 -5.517896 180)
			(unlocked yes)
			(layer "F.Fab")
			(hide yes)
			(effects
				(font
					(size 1.016 1.016)
					(thickness 0.1524)
				)
			)
		)
		(duplicate_pad_numbers_are_jumpers no)
		(fp_line
			(start 0.508 -0.9398)
			(end -0.508 -0.9398)
			(stroke
				(width 0.1524)
				(type default)
			)
			(layer "F.SilkS")
		)
		(fp_line
			(start -0.508 -0.9398)
			(end -0.508 0.9398)
			(stroke
				(width 0.1524)
				(type default)
			)
			(layer "F.SilkS")
		)
		(fp_rect
			(start -0.508 0.9398)
			(end 0.508 -0.9398)
			(stroke
				(width 0)
				(type default)
			)
			(fill no)
			(layer "F.CrtYd")
		)
		(fp_rect
			(start -0.508 0.9398)
			(end 0.508 -0.9398)
			(stroke
				(width 0)
				(type default)
			)
			(fill no)
			(layer "F.Fab")
		)
		(pad "1" smd custom
			(at 0 -0.4445 180)
			(size 0.1397 0.1397)
			(layers "F.Cu" "F.Mask" "F.Paste")
			(net "PWM_OUT_FAN4_NET")
			(options
				(clearance outline)
				(anchor circle)
			)
			(primitives
				(gr_poly
					(pts
						(arc
							(start -0.1778 -0.2794)
							(mid -0.249642 -0.249642)
							(end -0.2794 -0.1778)
						)
						(arc
							(start -0.2794 0.1778)
							(mid -0.249642 0.249642)
							(end -0.1778 0.2794)
						)
						(arc
							(start 0.1778 0.2794)
							(mid 0.249642 0.249642)
							(end 0.2794 0.1778)
						)
						(arc
							(start 0.2794 -0.1778)
							(mid 0.249642 -0.249642)
							(end 0.1778 -0.2794)
						)
					)
					(width 0)
					(fill yes)
				)
			)
		)
		(pad "2" smd custom
			(at 0 0.4445 180)
			(size 0.1397 0.1397)
			(layers "F.Cu" "F.Mask" "F.Paste")
			(net "PWM_OUT_FAN4")
			(options
				(clearance outline)
				(anchor circle)
			)
			(primitives
				(gr_poly
					(pts
						(arc
							(start -0.1778 -0.2794)
							(mid -0.249642 -0.249642)
							(end -0.2794 -0.1778)
						)
						(arc
							(start -0.2794 0.1778)
							(mid -0.249642 0.249642)
							(end -0.1778 0.2794)
						)
						(arc
							(start 0.1778 0.2794)
							(mid 0.249642 0.249642)
							(end 0.2794 0.1778)
						)
						(arc
							(start 0.2794 -0.1778)
							(mid 0.249642 -0.249642)
							(end 0.1778 -0.2794)
						)
					)
					(width 0)
					(fill yes)
				)
			)
		)
	)
	(footprint ""
		(layer "F.Cu")
		(at 25.527 -361.188)
		(property "Reference" "PR9"
			(at 0 0 0)
			(layer "F.SilkS")
			(hide yes)
			(effects
				(font
					(size 1.27 1.27)
				)
			)
		)
		(property "Value" "0R2J-2-GP"
			(at 0.064008 -3.993896 0)
			(unlocked yes)
			(layer "F.Fab")
			(hide yes)
			(effects
				(font
					(size 1.016 1.016)
					(thickness 0.1524)
				)
			)
		)
		(property "Device Type" "R402H16"
			(at 0.064008 -5.517896 0)
			(unlocked yes)
			(layer "F.Fab")
			(hide yes)
			(effects
				(font
					(size 1.016 1.016)
					(thickness 0.1524)
				)
			)
		)
		(duplicate_pad_numbers_are_jumpers no)
		(fp_line
			(start -0.508 -0.9398)
			(end -0.508 0.9398)
			(stroke
				(width 0.1524)
				(type default)
			)
			(layer "F.SilkS")
		)
		(fp_line
			(start 0.508 -0.9398)
			(end -0.508 -0.9398)
			(stroke
				(width 0.1524)
				(type default)
			)
			(layer "F.SilkS")
		)
		(fp_rect
			(start -0.508 0.9398)
			(end 0.508 -0.9398)
			(stroke
				(width 0)
				(type default)
			)
			(fill no)
			(layer "F.CrtYd")
		)
		(fp_rect
			(start -0.508 0.9398)
			(end 0.508 -0.9398)
			(stroke
				(width 0)
				(type default)
			)
			(fill no)
			(layer "F.Fab")
		)
		(pad "1" smd custom
			(at 0 -0.4445)
			(size 0.1397 0.1397)
			(layers "F.Cu" "F.Mask" "F.Paste")
			(net "ADM1276_LATCH#")
			(options
				(clearance outline)
				(anchor circle)
			)
			(primitives
				(gr_poly
					(pts
						(arc
							(start -0.1778 -0.2794)
							(mid -0.249642 -0.249642)
							(end -0.2794 -0.1778)
						)
						(arc
							(start -0.2794 0.1778)
							(mid -0.249642 0.249642)
							(end -0.1778 0.2794)
						)
						(arc
							(start 0.1778 0.2794)
							(mid 0.249642 0.249642)
							(end 0.2794 0.1778)
						)
						(arc
							(start 0.2794 -0.1778)
							(mid 0.249642 -0.249642)
							(end 0.1778 -0.2794)
						)
					)
					(width 0)
					(fill yes)
				)
			)
		)
		(pad "2" smd custom
			(at 0 0.4445)
			(size 0.1397 0.1397)
			(layers "F.Cu" "F.Mask" "F.Paste")
			(net "ADM1276_UV")
			(options
				(clearance outline)
				(anchor circle)
			)
			(primitives
				(gr_poly
					(pts
						(arc
							(start -0.1778 -0.2794)
							(mid -0.249642 -0.249642)
							(end -0.2794 -0.1778)
						)
						(arc
							(start -0.2794 0.1778)
							(mid -0.249642 0.249642)
							(end -0.1778 0.2794)
						)
						(arc
							(start 0.1778 0.2794)
							(mid 0.249642 0.249642)
							(end 0.2794 0.1778)
						)
						(arc
							(start 0.2794 -0.1778)
							(mid 0.249642 -0.249642)
							(end 0.1778 -0.2794)
						)
					)
					(width 0)
					(fill yes)
				)
			)
		)
	)
	(footprint ""
		(layer "F.Cu")
		(at 15.9004 -62.865 180)
		(property "Reference" "R61"
			(at 0 0 180)
			(layer "F.SilkS")
			(hide yes)
			(effects
				(font
					(size 1.27 1.27)
				)
			)
		)
		(property "Value" "4K7R2F-GP"
			(at 0.064008 -3.993896 180)
			(unlocked yes)
			(layer "F.Fab")
			(hide yes)
			(effects
				(font
					(size 1.016 1.016)
					(thickness 0.1524)
				)
			)
		)
		(property "Device Type" "R402H16"
			(at 0.064008 -5.517896 180)
			(unlocked yes)
			(layer "F.Fab")
			(hide yes)
			(effects
				(font
					(size 1.016 1.016)
					(thickness 0.1524)
				)
			)
		)
		(duplicate_pad_numbers_are_jumpers no)
		(fp_line
			(start 0.508 -0.9398)
			(end -0.508 -0.9398)
			(stroke
				(width 0.1524)
				(type default)
			)
			(layer "F.SilkS")
		)
		(fp_line
			(start -0.508 -0.9398)
			(end -0.508 0.9398)
			(stroke
				(width 0.1524)
				(type default)
			)
			(layer "F.SilkS")
		)
		(fp_rect
			(start -0.508 0.9398)
			(end 0.508 -0.9398)
			(stroke
				(width 0)
				(type default)
			)
			(fill no)
			(layer "F.CrtYd")
		)
		(fp_rect
			(start -0.508 0.9398)
			(end 0.508 -0.9398)
			(stroke
				(width 0)
				(type default)
			)
			(fill no)
			(layer "F.Fab")
		)
		(pad "1" smd custom
			(at 0 -0.4445 180)
			(size 0.1397 0.1397)
			(layers "F.Cu" "F.Mask" "F.Paste")
			(net "P3V3")
			(options
				(clearance outline)
				(anchor circle)
			)
			(primitives
				(gr_poly
					(pts
						(arc
							(start -0.1778 -0.2794)
							(mid -0.249642 -0.249642)
							(end -0.2794 -0.1778)
						)
						(arc
							(start -0.2794 0.1778)
							(mid -0.249642 0.249642)
							(end -0.1778 0.2794)
						)
						(arc
							(start 0.1778 0.2794)
							(mid 0.249642 0.249642)
							(end 0.2794 0.1778)
						)
						(arc
							(start 0.2794 -0.1778)
							(mid 0.249642 -0.249642)
							(end 0.1778 -0.2794)
						)
					)
					(width 0)
					(fill yes)
				)
			)
		)
		(pad "2" smd custom
			(at 0 0.4445 180)
			(size 0.1397 0.1397)
			(layers "F.Cu" "F.Mask" "F.Paste")
			(net "I2C_C_SCL_CONN_R")
			(options
				(clearance outline)
				(anchor circle)
			)
			(primitives
				(gr_poly
					(pts
						(arc
							(start -0.1778 -0.2794)
							(mid -0.249642 -0.249642)
							(end -0.2794 -0.1778)
						)
						(arc
							(start -0.2794 0.1778)
							(mid -0.249642 0.249642)
							(end -0.1778 0.2794)
						)
						(arc
							(start 0.1778 0.2794)
							(mid 0.249642 0.249642)
							(end 0.2794 0.1778)
						)
						(arc
							(start 0.2794 -0.1778)
							(mid 0.249642 -0.249642)
							(end 0.1778 -0.2794)
						)
					)
					(width 0)
					(fill yes)
				)
			)
		)
	)
	(footprint ""
		(layer "F.Cu")
		(at 40.851074 -362.859574 180)
		(property "Reference" "PR41"
			(at 0 0 180)
			(layer "F.SilkS")
			(hide yes)
			(effects
				(font
					(size 1.27 1.27)
				)
			)
		)
		(property "Value" "1KR2F-3-GP"
			(at 0.064008 -3.993896 180)
			(unlocked yes)
			(layer "F.Fab")
			(hide yes)
			(effects
				(font
					(size 1.016 1.016)
					(thickness 0.1524)
				)
			)
		)
		(property "Device Type" "R402H16"
			(at 0.064008 -5.517896 180)
			(unlocked yes)
			(layer "F.Fab")
			(hide yes)
			(effects
				(font
					(size 1.016 1.016)
					(thickness 0.1524)
				)
			)
		)
		(duplicate_pad_numbers_are_jumpers no)
		(fp_line
			(start 0.508 -0.9398)
			(end -0.508 -0.9398)
			(stroke
				(width 0.1524)
				(type default)
			)
			(layer "F.SilkS")
		)
		(fp_line
			(start -0.508 -0.9398)
			(end -0.508 0.9398)
			(stroke
				(width 0.1524)
				(type default)
			)
			(layer "F.SilkS")
		)
		(fp_rect
			(start -0.508 0.9398)
			(end 0.508 -0.9398)
			(stroke
				(width 0)
				(type default)
			)
			(fill no)
			(layer "F.CrtYd")
		)
		(fp_rect
			(start -0.508 0.9398)
			(end 0.508 -0.9398)
			(stroke
				(width 0)
				(type default)
			)
			(fill no)
			(layer "F.Fab")
		)
		(pad "1" smd custom
			(at 0 -0.4445 180)
			(size 0.1397 0.1397)
			(layers "F.Cu" "F.Mask" "F.Paste")
			(net "TEMP_ALM#_JP_1")
			(options
				(clearance outline)
				(anchor circle)
			)
			(primitives
				(gr_poly
					(pts
						(arc
							(start -0.1778 -0.2794)
							(mid -0.249642 -0.249642)
							(end -0.2794 -0.1778)
						)
						(arc
							(start -0.2794 0.1778)
							(mid -0.249642 0.249642)
							(end -0.1778 0.2794)
						)
						(arc
							(start 0.1778 0.2794)
							(mid 0.249642 0.249642)
							(end 0.2794 0.1778)
						)
						(arc
							(start 0.2794 -0.1778)
							(mid 0.249642 -0.249642)
							(end 0.1778 -0.2794)
						)
					)
					(width 0)
					(fill yes)
				)
			)
		)
		(pad "2" smd custom
			(at 0 0.4445 180)
			(size 0.1397 0.1397)
			(layers "F.Cu" "F.Mask" "F.Paste")
			(net "ADM1276_LATCH#")
			(options
				(clearance outline)
				(anchor circle)
			)
			(primitives
				(gr_poly
					(pts
						(arc
							(start -0.1778 -0.2794)
							(mid -0.249642 -0.249642)
							(end -0.2794 -0.1778)
						)
						(arc
							(start -0.2794 0.1778)
							(mid -0.249642 0.249642)
							(end -0.1778 0.2794)
						)
						(arc
							(start 0.1778 0.2794)
							(mid 0.249642 0.249642)
							(end 0.2794 0.1778)
						)
						(arc
							(start 0.2794 -0.1778)
							(mid 0.249642 -0.249642)
							(end 0.1778 -0.2794)
						)
					)
					(width 0)
					(fill yes)
				)
			)
		)
	)
)
